(kicad_pcb
	(version 20260206)
	(generator "pcbnew")
	(generator_version "10.0")
	(general
		(thickness 1.6)
		(legacy_teardrops no)
	)
	(paper "A4")
	(title_block
		(title "04192023_DAF0TMB3IC0_F0TG_MB_C_brd_V02_OCP.brd")
		(comment 1 "Grand Teton / footprints 780-785 of 8354")
	)
	(layers
		(0 "F.Cu" signal "TOP")
		(4 "In1.Cu" signal "GND")
		(6 "In2.Cu" signal "IN1")
		(8 "In3.Cu" signal "GND1")
		(10 "In4.Cu" signal "IN2")
		(12 "In5.Cu" signal "GND2")
		(14 "In6.Cu" signal "IN3")
		(16 "In7.Cu" signal "GND3")
		(18 "In8.Cu" signal "VCC")
		(20 "In9.Cu" signal "VCC1")
		(22 "In10.Cu" signal "GND4")
		(24 "In11.Cu" signal "IN4")
		(26 "In12.Cu" signal "GND5")
		(28 "In13.Cu" signal "IN5")
		(30 "In14.Cu" signal "GND6")
		(32 "In15.Cu" signal "IN6")
		(34 "In16.Cu" signal "GND7")
		(2 "B.Cu" signal "BOTTOM")
		(9 "F.Adhes" user "F.Adhesive")
		(11 "B.Adhes" user "B.Adhesive")
		(13 "F.Paste" user "Package Geometry/Pastemask Top")
		(15 "B.Paste" user "Package Geometry/Pastemask Bottom")
		(5 "F.SilkS" user "Ref Des/Silkscreen Top")
		(7 "B.SilkS" user "Ref Des/Silkscreen Bottom")
		(1 "F.Mask" user "Board Geometry/Soldermask Top")
		(3 "B.Mask" user "Board Geometry/Soldermask Bottom")
		(17 "Dwgs.User" user "User.Drawings")
		(19 "Cmts.User" user "User.Comments")
		(21 "Eco1.User" user "User.Eco1")
		(23 "Eco2.User" user "User.Eco2")
		(25 "Edge.Cuts" user "Board Geometry/Outline")
		(27 "Margin" user)
		(31 "F.CrtYd" user "Package Geometry/Place Bound Top")
		(29 "B.CrtYd" user "Package Geometry/Place Bound Bottom")
		(35 "F.Fab" user "Ref Des/Assembly Top")
		(33 "B.Fab" user "Ref Des/Assembly Bottom")
	)
	(footprint ""
		(layer "F.Cu")
		(at 210.74888 -44.795948)
		(property "Reference" "R3531"
			(at 0 0 0)
			(layer "F.SilkS")
			(hide yes)
			(effects
				(font
					(size 1.27 1.27)
				)
			)
		)
		(property "Value" ""
			(at 0 0 0)
			(layer "F.Fab")
			(effects
				(font
					(size 1.27 1.27)
				)
			)
		)
		(duplicate_pad_numbers_are_jumpers no)
		(fp_line
			(start -0.7874 -0.4064)
			(end 0.7874 -0.4064)
			(stroke
				(width 0.1524)
				(type default)
			)
			(layer "F.SilkS")
		)
		(fp_line
			(start -0.7874 0.4064)
			(end -0.7874 -0.4064)
			(stroke
				(width 0.1524)
				(type default)
			)
			(layer "F.SilkS")
		)
		(fp_line
			(start 0.7874 -0.4064)
			(end 0.7874 0.4064)
			(stroke
				(width 0.1524)
				(type default)
			)
			(layer "F.SilkS")
		)
		(fp_line
			(start 0.7874 0.4064)
			(end -0.7874 0.4064)
			(stroke
				(width 0.1524)
				(type default)
			)
			(layer "F.SilkS")
		)
		(fp_line
			(start -0.67945 -0.305054)
			(end -0.12065 -0.305054)
			(stroke
				(width 0.1)
				(type default)
			)
			(layer "F.Fab")
		)
		(fp_line
			(start -0.67945 0.3048)
			(end -0.67945 -0.305054)
			(stroke
				(width 0.1)
				(type default)
			)
			(layer "F.Fab")
		)
		(fp_line
			(start -0.12065 -0.305054)
			(end -0.12065 -0.2794)
			(stroke
				(width 0.1)
				(type default)
			)
			(layer "F.Fab")
		)
		(fp_line
			(start -0.12065 -0.2794)
			(end 0.12065 -0.2794)
			(stroke
				(width 0.1)
				(type default)
			)
			(layer "F.Fab")
		)
		(fp_line
			(start -0.12065 0.2794)
			(end -0.12065 0.3048)
			(stroke
				(width 0.1)
				(type default)
			)
			(layer "F.Fab")
		)
		(fp_line
			(start -0.12065 0.3048)
			(end -0.67945 0.3048)
			(stroke
				(width 0.1)
				(type default)
			)
			(layer "F.Fab")
		)
		(fp_line
			(start 0.120396 0.2794)
			(end -0.12065 0.2794)
			(stroke
				(width 0.1)
				(type default)
			)
			(layer "F.Fab")
		)
		(fp_line
			(start 0.120396 0.3048)
			(end 0.120396 0.2794)
			(stroke
				(width 0.1)
				(type default)
			)
			(layer "F.Fab")
		)
		(fp_line
			(start 0.12065 -0.3048)
			(end 0.67945 -0.3048)
			(stroke
				(width 0.1)
				(type default)
			)
			(layer "F.Fab")
		)
		(fp_line
			(start 0.12065 -0.2794)
			(end 0.12065 -0.3048)
			(stroke
				(width 0.1)
				(type default)
			)
			(layer "F.Fab")
		)
		(fp_line
			(start 0.67945 -0.3048)
			(end 0.67945 0.3048)
			(stroke
				(width 0.1)
				(type default)
			)
			(layer "F.Fab")
		)
		(fp_line
			(start 0.67945 0.3048)
			(end 0.120396 0.3048)
			(stroke
				(width 0.1)
				(type default)
			)
			(layer "F.Fab")
		)
		(pad "1" smd circle
			(at -0.40005 0)
			(size 0 0)
			(layers "F.Cu" "F.Mask" "F.Paste")
			(net "SMB_PCIE_E1S_ISO_EN")
		)
		(pad "2" smd circle
			(at 0.40005 0)
			(size 0 0)
			(layers "F.Cu" "F.Mask" "F.Paste")
			(net "SMB_PCIE_E1S_ISO_EN_R")
		)
	)
	(footprint ""
		(layer "F.Cu")
		(at 258.12496 -360.764074)
		(property "Reference" "H112"
			(at -4.58216 -9.007856 0)
			(unlocked yes)
			(layer "F.SilkS")
			(effects
				(font
					(size 0.7874 0.5842)
					(thickness 0.1524)
				)
				(justify left)
			)
		)
		(property "Value" ""
			(at 0 0 0)
			(layer "F.Fab")
			(effects
				(font
					(size 1.27 1.27)
				)
			)
		)
		(duplicate_pad_numbers_are_jumpers no)
		(fp_circle
			(center 0 0)
			(end 7.999984 0)
			(stroke
				(width 0.1524)
				(type default)
			)
			(fill no)
			(layer "F.SilkS")
		)
		(fp_circle
			(center 0 0)
			(end 7.999984 0)
			(stroke
				(width 0.1524)
				(type default)
			)
			(fill no)
			(layer "B.SilkS")
		)
		(fp_circle
			(center 0 0)
			(end 7.999984 0)
			(stroke
				(width 0.1)
				(type default)
			)
			(fill no)
			(layer "B.Fab")
		)
		(fp_circle
			(center 0 0)
			(end 7.999984 0)
			(stroke
				(width 0.1)
				(type default)
			)
			(fill no)
			(layer "F.Fab")
		)
		(pad "" np_thru_hole circle
			(at 0 0)
			(size 4.0132 4.0132)
			(drill 4.0132)
			(layers "*.Cu" "*.Mask")
			(clearance 0.381)
			(thermal_gap 0.381)
		)
		(pad "2" thru_hole circle
			(at 3.2639 0)
			(size 0.9144 0.9144)
			(drill 0.5588)
			(layers "*.Cu" "*.Mask")
			(remove_unused_layers no)
			(net "GND")
			(clearance 0.0762)
			(thermal_gap 0.0762)
		)
		(pad "3" thru_hole circle
			(at 2.307844 -2.307844)
			(size 0.9144 0.9144)
			(drill 0.5588)
			(layers "*.Cu" "*.Mask")
			(remove_unused_layers no)
			(net "GND")
			(clearance 0.0762)
			(thermal_gap 0.0762)
		)
		(pad "4" thru_hole circle
			(at 0 -3.2639)
			(size 0.9144 0.9144)
			(drill 0.5588)
			(layers "*.Cu" "*.Mask")
			(remove_unused_layers no)
			(net "GND")
			(clearance 0.0762)
			(thermal_gap 0.0762)
		)
		(pad "5" thru_hole circle
			(at -2.307844 -2.307844)
			(size 0.9144 0.9144)
			(drill 0.5588)
			(layers "*.Cu" "*.Mask")
			(remove_unused_layers no)
			(net "GND")
			(clearance 0.0762)
			(thermal_gap 0.0762)
		)
		(pad "6" thru_hole circle
			(at -3.2639 0)
			(size 0.9144 0.9144)
			(drill 0.5588)
			(layers "*.Cu" "*.Mask")
			(remove_unused_layers no)
			(net "GND")
			(clearance 0.0762)
			(thermal_gap 0.0762)
		)
		(pad "7" thru_hole circle
			(at -2.307844 2.307844)
			(size 0.9144 0.9144)
			(drill 0.5588)
			(layers "*.Cu" "*.Mask")
			(remove_unused_layers no)
			(net "GND")
			(clearance 0.0762)
			(thermal_gap 0.0762)
		)
		(pad "8" thru_hole circle
			(at 0 3.2639)
			(size 0.9144 0.9144)
			(drill 0.5588)
			(layers "*.Cu" "*.Mask")
			(remove_unused_layers no)
			(net "GND")
			(clearance 0.0762)
			(thermal_gap 0.0762)
		)
		(pad "9" thru_hole circle
			(at 2.307844 2.307844)
			(size 0.9144 0.9144)
			(drill 0.5588)
			(layers "*.Cu" "*.Mask")
			(remove_unused_layers no)
			(net "GND")
			(clearance 0.0762)
			(thermal_gap 0.0762)
		)
		(zone
			(layer "F.Cu")
			(hatch none 0.5)
			(connect_pads
				(clearance 0)
			)
			(min_thickness 0.25)
			(keepout
				(tracks not_allowed)
				(vias allowed)
				(pads allowed)
				(copperpour not_allowed)
				(footprints allowed)
			)
			(placement
				(enabled no)
				(sheetname "")
			)
			(fill
				(thermal_gap 0.5)
				(thermal_bridge_width 0.5)
				(island_removal_mode 0)
			)
			(polygon
				(pts
					(arc
						(start 258.12496 -356.496874)
						(mid 253.85776 -360.764074)
						(end 258.12496 -365.031274)
					)
					(arc
						(start 258.12496 -368.764058)
						(mid 252.468117 -366.420917)
						(end 250.124976 -360.764074)
					)
					(arc
						(start 250.124976 -360.764074)
						(mid 252.468117 -355.107231)
						(end 258.12496 -352.76409)
					)
				)
			)
		)
		(zone
			(layer "F.Cu")
			(hatch none 0.5)
			(connect_pads
				(clearance 0)
			)
			(min_thickness 0.25)
			(keepout
				(tracks not_allowed)
				(vias allowed)
				(pads allowed)
				(copperpour not_allowed)
				(footprints allowed)
			)
			(placement
				(enabled no)
				(sheetname "")
			)
			(fill
				(thermal_gap 0.5)
				(thermal_bridge_width 0.5)
				(island_removal_mode 0)
			)
			(polygon
				(pts
					(arc
						(start 258.12496 -356.496874)
						(mid 262.39216 -360.764074)
						(end 258.12496 -365.031274)
					)
					(arc
						(start 258.12496 -368.764058)
						(mid 263.781803 -366.420917)
						(end 266.124944 -360.764074)
					)
					(arc
						(start 266.124944 -360.764074)
						(mid 263.781803 -355.107231)
						(end 258.12496 -352.76409)
					)
				)
			)
		)
		(zone
			(layers "F.Cu" "B.Cu" "In1.Cu" "In2.Cu" "In3.Cu" "In4.Cu" "In5.Cu" "In6.Cu"
				"In7.Cu" "In8.Cu" "In9.Cu" "In10.Cu" "In11.Cu" "In12.Cu" "In13.Cu" "In14.Cu"
				"In15.Cu" "In16.Cu"
			)
			(hatch none 0.5)
			(connect_pads
				(clearance 0)
			)
			(min_thickness 0.25)
			(keepout
				(tracks not_allowed)
				(vias allowed)
				(pads allowed)
				(copperpour not_allowed)
				(footprints allowed)
			)
			(placement
				(enabled no)
				(sheetname "")
			)
			(fill
				(thermal_gap 0.5)
				(thermal_bridge_width 0.5)
				(island_removal_mode 0)
			)
			(polygon
				(pts
					(arc
						(start 260.63702 -360.764074)
						(mid 255.6129 -360.764074)
						(end 260.63702 -360.764074)
					)
				)
			)
		)
	)
	(footprint ""
		(layer "F.Cu")
		(at 395.751558 -323.796152 90)
		(property "Reference" "R1503"
			(at 0 0 90)
			(layer "F.SilkS")
			(hide yes)
			(effects
				(font
					(size 1.27 1.27)
				)
			)
		)
		(property "Value" ""
			(at 0 0 90)
			(layer "F.Fab")
			(effects
				(font
					(size 1.27 1.27)
				)
			)
		)
		(duplicate_pad_numbers_are_jumpers no)
		(fp_line
			(start 0.7874 -0.4064)
			(end 0.7874 0.4064)
			(stroke
				(width 0.1524)
				(type default)
			)
			(layer "F.SilkS")
		)
		(fp_line
			(start -0.7874 -0.4064)
			(end 0.7874 -0.4064)
			(stroke
				(width 0.1524)
				(type default)
			)
			(layer "F.SilkS")
		)
		(fp_line
			(start 0.7874 0.4064)
			(end -0.7874 0.4064)
			(stroke
				(width 0.1524)
				(type default)
			)
			(layer "F.SilkS")
		)
		(fp_line
			(start -0.7874 0.4064)
			(end -0.7874 -0.4064)
			(stroke
				(width 0.1524)
				(type default)
			)
			(layer "F.SilkS")
		)
		(fp_line
			(start -0.12065 -0.305054)
			(end -0.12065 -0.2794)
			(stroke
				(width 0.1)
				(type default)
			)
			(layer "F.Fab")
		)
		(fp_line
			(start -0.67945 -0.305054)
			(end -0.12065 -0.305054)
			(stroke
				(width 0.1)
				(type default)
			)
			(layer "F.Fab")
		)
		(fp_line
			(start 0.67945 -0.3048)
			(end 0.67945 0.3048)
			(stroke
				(width 0.1)
				(type default)
			)
			(layer "F.Fab")
		)
		(fp_line
			(start 0.12065 -0.3048)
			(end 0.67945 -0.3048)
			(stroke
				(width 0.1)
				(type default)
			)
			(layer "F.Fab")
		)
		(fp_line
			(start 0.12065 -0.2794)
			(end 0.12065 -0.3048)
			(stroke
				(width 0.1)
				(type default)
			)
			(layer "F.Fab")
		)
		(fp_line
			(start -0.12065 -0.2794)
			(end 0.12065 -0.2794)
			(stroke
				(width 0.1)
				(type default)
			)
			(layer "F.Fab")
		)
		(fp_line
			(start 0.120396 0.2794)
			(end -0.12065 0.2794)
			(stroke
				(width 0.1)
				(type default)
			)
			(layer "F.Fab")
		)
		(fp_line
			(start -0.12065 0.2794)
			(end -0.12065 0.3048)
			(stroke
				(width 0.1)
				(type default)
			)
			(layer "F.Fab")
		)
		(fp_line
			(start 0.67945 0.3048)
			(end 0.120396 0.3048)
			(stroke
				(width 0.1)
				(type default)
			)
			(layer "F.Fab")
		)
		(fp_line
			(start 0.120396 0.3048)
			(end 0.120396 0.2794)
			(stroke
				(width 0.1)
				(type default)
			)
			(layer "F.Fab")
		)
		(fp_line
			(start -0.12065 0.3048)
			(end -0.67945 0.3048)
			(stroke
				(width 0.1)
				(type default)
			)
			(layer "F.Fab")
		)
		(fp_line
			(start -0.67945 0.3048)
			(end -0.67945 -0.305054)
			(stroke
				(width 0.1)
				(type default)
			)
			(layer "F.Fab")
		)
		(pad "1" smd circle
			(at -0.40005 0 90)
			(size 0 0)
			(layers "F.Cu" "F.Mask" "F.Paste")
			(net "PVDD18_S5_P0")
		)
		(pad "2" smd circle
			(at 0.40005 0 90)
			(size 0 0)
			(layers "F.Cu" "F.Mask" "F.Paste")
			(net "ESPI_CPU0_D0")
		)
	)
	(footprint ""
		(layer "F.Cu")
		(at 30.936692 -397.396462)
		(property "Reference" "PC6637_2"
			(at 0 0 0)
			(layer "F.SilkS")
			(hide yes)
			(effects
				(font
					(size 1.27 1.27)
				)
			)
		)
		(property "Value" ""
			(at 0 0 0)
			(layer "F.Fab")
			(effects
				(font
					(size 1.27 1.27)
				)
			)
		)
		(duplicate_pad_numbers_are_jumpers no)
		(fp_line
			(start -1.524 -0.762)
			(end 1.524 -0.762)
			(stroke
				(width 0.1524)
				(type default)
			)
			(layer "F.SilkS")
		)
		(fp_line
			(start -1.524 0.762)
			(end -1.524 -0.762)
			(stroke
				(width 0.1524)
				(type default)
			)
			(layer "F.SilkS")
		)
		(fp_line
			(start 1.524 -0.762)
			(end 1.524 0.762)
			(stroke
				(width 0.1524)
				(type default)
			)
			(layer "F.SilkS")
		)
		(fp_line
			(start 1.524 0.762)
			(end -1.524 0.762)
			(stroke
				(width 0.1524)
				(type default)
			)
			(layer "F.SilkS")
		)
		(fp_line
			(start -1.1049 -0.724916)
			(end -1.1049 0.724916)
			(stroke
				(width 0.1)
				(type default)
			)
			(layer "F.Fab")
		)
		(fp_line
			(start -1.1049 0.724916)
			(end 1.1049 0.724916)
			(stroke
				(width 0.1)
				(type default)
			)
			(layer "F.Fab")
		)
		(fp_line
			(start 1.1049 -0.724916)
			(end -1.1049 -0.724916)
			(stroke
				(width 0.1)
				(type default)
			)
			(layer "F.Fab")
		)
		(fp_line
			(start 1.1049 0.724916)
			(end 1.1049 -0.724916)
			(stroke
				(width 0.1)
				(type default)
			)
			(layer "F.Fab")
		)
		(pad "1" smd rect
			(at -0.889 0 180)
			(size 1.016 1.27)
			(layers "F.Cu" "F.Mask" "F.Paste")
			(net "SW_P12V_AUX_P0V9_RETIMER_CPU1_FLT")
		)
		(pad "2" smd rect
			(at 0.889 0 180)
			(size 1.016 1.27)
			(layers "F.Cu" "F.Mask" "F.Paste")
			(net "GND")
		)
	)
	(footprint ""
		(layer "F.Cu")
		(at 140.886942 -105.225596)
		(property "Reference" "R3296"
			(at 0 0 0)
			(layer "F.SilkS")
			(hide yes)
			(effects
				(font
					(size 1.27 1.27)
				)
			)
		)
		(property "Value" ""
			(at 0 0 0)
			(layer "F.Fab")
			(effects
				(font
					(size 1.27 1.27)
				)
			)
		)
		(duplicate_pad_numbers_are_jumpers no)
		(fp_line
			(start -0.7874 -0.4064)
			(end 0.7874 -0.4064)
			(stroke
				(width 0.1524)
				(type default)
			)
			(layer "F.SilkS")
		)
		(fp_line
			(start -0.7874 0.4064)
			(end -0.7874 -0.4064)
			(stroke
				(width 0.1524)
				(type default)
			)
			(layer "F.SilkS")
		)
		(fp_line
			(start 0.7874 -0.4064)
			(end 0.7874 0.4064)
			(stroke
				(width 0.1524)
				(type default)
			)
			(layer "F.SilkS")
		)
		(fp_line
			(start 0.7874 0.4064)
			(end -0.7874 0.4064)
			(stroke
				(width 0.1524)
				(type default)
			)
			(layer "F.SilkS")
		)
		(fp_line
			(start -0.67945 -0.305054)
			(end -0.12065 -0.305054)
			(stroke
				(width 0.1)
				(type default)
			)
			(layer "F.Fab")
		)
		(fp_line
			(start -0.67945 0.3048)
			(end -0.67945 -0.305054)
			(stroke
				(width 0.1)
				(type default)
			)
			(layer "F.Fab")
		)
		(fp_line
			(start -0.12065 -0.305054)
			(end -0.12065 -0.2794)
			(stroke
				(width 0.1)
				(type default)
			)
			(layer "F.Fab")
		)
		(fp_line
			(start -0.12065 -0.2794)
			(end 0.12065 -0.2794)
			(stroke
				(width 0.1)
				(type default)
			)
			(layer "F.Fab")
		)
		(fp_line
			(start -0.12065 0.2794)
			(end -0.12065 0.3048)
			(stroke
				(width 0.1)
				(type default)
			)
			(layer "F.Fab")
		)
		(fp_line
			(start -0.12065 0.3048)
			(end -0.67945 0.3048)
			(stroke
				(width 0.1)
				(type default)
			)
			(layer "F.Fab")
		)
		(fp_line
			(start 0.120396 0.2794)
			(end -0.12065 0.2794)
			(stroke
				(width 0.1)
				(type default)
			)
			(layer "F.Fab")
		)
		(fp_line
			(start 0.120396 0.3048)
			(end 0.120396 0.2794)
			(stroke
				(width 0.1)
				(type default)
			)
			(layer "F.Fab")
		)
		(fp_line
			(start 0.12065 -0.3048)
			(end 0.67945 -0.3048)
			(stroke
				(width 0.1)
				(type default)
			)
			(layer "F.Fab")
		)
		(fp_line
			(start 0.12065 -0.2794)
			(end 0.12065 -0.3048)
			(stroke
				(width 0.1)
				(type default)
			)
			(layer "F.Fab")
		)
		(fp_line
			(start 0.67945 -0.3048)
			(end 0.67945 0.3048)
			(stroke
				(width 0.1)
				(type default)
			)
			(layer "F.Fab")
		)
		(fp_line
			(start 0.67945 0.3048)
			(end 0.120396 0.3048)
			(stroke
				(width 0.1)
				(type default)
			)
			(layer "F.Fab")
		)
		(pad "1" smd circle
			(at -0.40005 0)
			(size 0 0)
			(layers "F.Cu" "F.Mask" "F.Paste")
			(net "P3V3_AUX")
		)
		(pad "2" smd circle
			(at 0.40005 0)
			(size 0 0)
			(layers "F.Cu" "F.Mask" "F.Paste")
			(net "HDD_ACTIVITY_BUF")
		)
	)
	(footprint ""
		(layer "F.Cu")
		(at 393.363958 -326.691752)
		(property "Reference" "R212"
			(at 0 0 0)
			(layer "F.SilkS")
			(hide yes)
			(effects
				(font
					(size 1.27 1.27)
				)
			)
		)
		(property "Value" ""
			(at 0 0 0)
			(layer "F.Fab")
			(effects
				(font
					(size 1.27 1.27)
				)
			)
		)
		(duplicate_pad_numbers_are_jumpers no)
		(fp_line
			(start -0.7874 -0.4064)
			(end 0.7874 -0.4064)
			(stroke
				(width 0.1524)
				(type default)
			)
			(layer "F.SilkS")
		)
		(fp_line
			(start -0.7874 0.4064)
			(end -0.7874 -0.4064)
			(stroke
				(width 0.1524)
				(type default)
			)
			(layer "F.SilkS")
		)
		(fp_line
			(start 0.7874 -0.4064)
			(end 0.7874 0.4064)
			(stroke
				(width 0.1524)
				(type default)
			)
			(layer "F.SilkS")
		)
		(fp_line
			(start 0.7874 0.4064)
			(end -0.7874 0.4064)
			(stroke
				(width 0.1524)
				(type default)
			)
			(layer "F.SilkS")
		)
		(fp_line
			(start -0.67945 -0.305054)
			(end -0.12065 -0.305054)
			(stroke
				(width 0.1)
				(type default)
			)
			(layer "F.Fab")
		)
		(fp_line
			(start -0.67945 0.3048)
			(end -0.67945 -0.305054)
			(stroke
				(width 0.1)
				(type default)
			)
			(layer "F.Fab")
		)
		(fp_line
			(start -0.12065 -0.305054)
			(end -0.12065 -0.2794)
			(stroke
				(width 0.1)
				(type default)
			)
			(layer "F.Fab")
		)
		(fp_line
			(start -0.12065 -0.2794)
			(end 0.12065 -0.2794)
			(stroke
				(width 0.1)
				(type default)
			)
			(layer "F.Fab")
		)
		(fp_line
			(start -0.12065 0.2794)
			(end -0.12065 0.3048)
			(stroke
				(width 0.1)
				(type default)
			)
			(layer "F.Fab")
		)
		(fp_line
			(start -0.12065 0.3048)
			(end -0.67945 0.3048)
			(stroke
				(width 0.1)
				(type default)
			)
			(layer "F.Fab")
		)
		(fp_line
			(start 0.120396 0.2794)
			(end -0.12065 0.2794)
			(stroke
				(width 0.1)
				(type default)
			)
			(layer "F.Fab")
		)
		(fp_line
			(start 0.120396 0.3048)
			(end 0.120396 0.2794)
			(stroke
				(width 0.1)
				(type default)
			)
			(layer "F.Fab")
		)
		(fp_line
			(start 0.12065 -0.3048)
			(end 0.67945 -0.3048)
			(stroke
				(width 0.1)
				(type default)
			)
			(layer "F.Fab")
		)
		(fp_line
			(start 0.12065 -0.2794)
			(end 0.12065 -0.3048)
			(stroke
				(width 0.1)
				(type default)
			)
			(layer "F.Fab")
		)
		(fp_line
			(start 0.67945 -0.3048)
			(end 0.67945 0.3048)
			(stroke
				(width 0.1)
				(type default)
			)
			(layer "F.Fab")
		)
		(fp_line
			(start 0.67945 0.3048)
			(end 0.120396 0.3048)
			(stroke
				(width 0.1)
				(type default)
			)
			(layer "F.Fab")
		)
		(pad "1" smd circle
			(at -0.40005 0)
			(size 0 0)
			(layers "F.Cu" "F.Mask" "F.Paste")
			(net "SMB_CPU_5_R_SCL")
		)
		(pad "2" smd circle
			(at 0.40005 0)
			(size 0 0)
			(layers "F.Cu" "F.Mask" "F.Paste")
			(net "SMB_CPU_5_SCL")
		)
	)
)
